(kicad_pcb
	(version 20260206)
	(generator "pcbnew")
	(generator_version "10.0")
	(general
		(thickness 1.6)
		(legacy_teardrops no)
	)
	(paper "A4")
	(title_block
		(title "03242023_DA0F0TMBIJ0_F0T_Motherboard_J_brd_V01_OCP.brd")
		(comment 1 "Grand Teton / footprints 5087-5092 of 6105")
	)
	(layers
		(0 "F.Cu" signal "TOP")
		(4 "In1.Cu" signal "GND")
		(6 "In2.Cu" signal "IN1")
		(8 "In3.Cu" signal "GND1")
		(10 "In4.Cu" signal "IN2")
		(12 "In5.Cu" signal "GND2")
		(14 "In6.Cu" signal "IN3")
		(16 "In7.Cu" signal "GND3")
		(18 "In8.Cu" signal "VCC")
		(20 "In9.Cu" signal "VCC1")
		(22 "In10.Cu" signal "GND4")
		(24 "In11.Cu" signal "IN4")
		(26 "In12.Cu" signal "GND5")
		(28 "In13.Cu" signal "IN5")
		(30 "In14.Cu" signal "GND6")
		(32 "In15.Cu" signal "IN6")
		(34 "In16.Cu" signal "GND7")
		(2 "B.Cu" signal "BOTTOM")
		(9 "F.Adhes" user "F.Adhesive")
		(11 "B.Adhes" user "B.Adhesive")
		(13 "F.Paste" user "Package Geometry/Pastemask Top")
		(15 "B.Paste" user "Package Geometry/Pastemask Bottom")
		(5 "F.SilkS" user "Ref Des/Silkscreen Top")
		(7 "B.SilkS" user "Ref Des/Silkscreen Bottom")
		(1 "F.Mask" user "Board Geometry/Soldermask Top")
		(3 "B.Mask" user "Board Geometry/Soldermask Bottom")
		(17 "Dwgs.User" user "User.Drawings")
		(19 "Cmts.User" user "User.Comments")
		(21 "Eco1.User" user "User.Eco1")
		(23 "Eco2.User" user "User.Eco2")
		(25 "Edge.Cuts" user "Board Geometry/Outline")
		(27 "Margin" user)
		(31 "F.CrtYd" user "Package Geometry/Place Bound Top")
		(29 "B.CrtYd" user "Package Geometry/Place Bound Bottom")
		(35 "F.Fab" user "Ref Des/Assembly Top")
		(33 "B.Fab" user "Ref Des/Assembly Bottom")
	)
	(footprint ""
		(layer "B.Cu")
		(at 116.40312 -244.82044 -90)
		(property "Reference" "C320"
			(at 0 0 90)
			(layer "B.SilkS")
			(hide yes)
			(effects
				(font
					(size 1.27 1.27)
				)
				(justify mirror)
			)
		)
		(property "Value" ""
			(at 0 0 90)
			(layer "B.Fab")
			(effects
				(font
					(size 1.27 1.27)
				)
				(justify mirror)
			)
		)
		(duplicate_pad_numbers_are_jumpers no)
		(fp_line
			(start -1.524 0.762)
			(end 1.524 0.762)
			(stroke
				(width 0.1524)
				(type default)
			)
			(layer "B.SilkS")
		)
		(fp_line
			(start 1.524 0.762)
			(end 1.524 -0.762)
			(stroke
				(width 0.1524)
				(type default)
			)
			(layer "B.SilkS")
		)
		(fp_line
			(start -1.524 -0.762)
			(end -1.524 0.762)
			(stroke
				(width 0.1524)
				(type default)
			)
			(layer "B.SilkS")
		)
		(fp_line
			(start 1.524 -0.762)
			(end -1.524 -0.762)
			(stroke
				(width 0.1524)
				(type default)
			)
			(layer "B.SilkS")
		)
		(fp_line
			(start -1.1049 0.724916)
			(end -1.1049 -0.724916)
			(stroke
				(width 0.1)
				(type default)
			)
			(layer "B.Fab")
		)
		(fp_line
			(start 1.1049 0.724916)
			(end -1.1049 0.724916)
			(stroke
				(width 0.1)
				(type default)
			)
			(layer "B.Fab")
		)
		(fp_line
			(start -1.1049 -0.724916)
			(end 1.1049 -0.724916)
			(stroke
				(width 0.1)
				(type default)
			)
			(layer "B.Fab")
		)
		(fp_line
			(start 1.1049 -0.724916)
			(end 1.1049 0.724916)
			(stroke
				(width 0.1)
				(type default)
			)
			(layer "B.Fab")
		)
		(pad "1" smd rect
			(at 0.889 0 270)
			(size 1.016 1.27)
			(layers "B.Cu" "B.Mask" "B.Paste")
			(net "PVCCIN_CPU1")
		)
		(pad "2" smd rect
			(at -0.889 0 270)
			(size 1.016 1.27)
			(layers "B.Cu" "B.Mask" "B.Paste")
			(net "GND")
		)
	)
	(footprint ""
		(layer "B.Cu")
		(at 23.240746 -321.554856 -90)
		(property "Reference" "C64"
			(at 0 0 90)
			(layer "B.SilkS")
			(hide yes)
			(effects
				(font
					(size 1.27 1.27)
				)
				(justify mirror)
			)
		)
		(property "Value" ""
			(at 0 0 90)
			(layer "B.Fab")
			(effects
				(font
					(size 1.27 1.27)
				)
				(justify mirror)
			)
		)
		(duplicate_pad_numbers_are_jumpers no)
		(fp_line
			(start -1.524 0.762)
			(end 1.524 0.762)
			(stroke
				(width 0.1524)
				(type default)
			)
			(layer "B.SilkS")
		)
		(fp_line
			(start 1.524 0.762)
			(end 1.524 -0.762)
			(stroke
				(width 0.1524)
				(type default)
			)
			(layer "B.SilkS")
		)
		(fp_line
			(start -1.524 -0.762)
			(end -1.524 0.762)
			(stroke
				(width 0.1524)
				(type default)
			)
			(layer "B.SilkS")
		)
		(fp_line
			(start 1.524 -0.762)
			(end -1.524 -0.762)
			(stroke
				(width 0.1524)
				(type default)
			)
			(layer "B.SilkS")
		)
		(fp_line
			(start -1.1049 0.724916)
			(end -1.1049 -0.724916)
			(stroke
				(width 0.1)
				(type default)
			)
			(layer "B.Fab")
		)
		(fp_line
			(start 1.1049 0.724916)
			(end -1.1049 0.724916)
			(stroke
				(width 0.1)
				(type default)
			)
			(layer "B.Fab")
		)
		(fp_line
			(start -1.1049 -0.724916)
			(end 1.1049 -0.724916)
			(stroke
				(width 0.1)
				(type default)
			)
			(layer "B.Fab")
		)
		(fp_line
			(start 1.1049 -0.724916)
			(end 1.1049 0.724916)
			(stroke
				(width 0.1)
				(type default)
			)
			(layer "B.Fab")
		)
		(pad "1" smd rect
			(at 0.889 0 270)
			(size 1.016 1.27)
			(layers "B.Cu" "B.Mask" "B.Paste")
			(net "P12V_S3_AUX_CPU1_NVDIMM")
		)
		(pad "2" smd rect
			(at -0.889 0 270)
			(size 1.016 1.27)
			(layers "B.Cu" "B.Mask" "B.Paste")
			(net "GND")
		)
	)
	(footprint ""
		(layer "B.Cu")
		(at 329.240388 8.003794)
		(property "Reference" "J120"
			(at 4.361942 1.648206 270)
			(unlocked yes)
			(layer "B.SilkS")
			(effects
				(font
					(size 0.7874 0.5842)
					(thickness 0.1524)
				)
				(justify left mirror)
			)
		)
		(property "Value" ""
			(at 0 0 0)
			(layer "B.Fab")
			(effects
				(font
					(size 1.27 1.27)
				)
				(justify mirror)
			)
		)
		(duplicate_pad_numbers_are_jumpers no)
		(fp_line
			(start -1.2192 -2.1082)
			(end -1.2192 2.1082)
			(stroke
				(width 0.1524)
				(type default)
			)
			(layer "B.SilkS")
		)
		(fp_line
			(start -1.2192 2.1082)
			(end 1.2192 2.1082)
			(stroke
				(width 0.1524)
				(type default)
			)
			(layer "B.SilkS")
		)
		(fp_line
			(start 1.2192 -2.1082)
			(end -1.2192 -2.1082)
			(stroke
				(width 0.1524)
				(type default)
			)
			(layer "B.SilkS")
		)
		(fp_line
			(start 1.2192 2.1082)
			(end 1.2192 -2.1082)
			(stroke
				(width 0.1524)
				(type default)
			)
			(layer "B.SilkS")
		)
		(pad "" np_thru_hole circle
			(at -3.4671 -1.27 270)
			(size 1.0414 1.0414)
			(drill 1.0414)
			(layers "*.Cu" "*.Mask")
			(clearance 0.381)
			(thermal_gap 0.381)
		)
		(pad "" np_thru_hole circle
			(at -3.4671 1.27 270)
			(size 1.0414 1.0414)
			(drill 1.0414)
			(layers "*.Cu" "*.Mask")
			(clearance 0.381)
			(thermal_gap 0.381)
		)
		(pad "" np_thru_hole circle
			(at 2.8829 -1.27 270)
			(size 1.0414 1.0414)
			(drill 1.0414)
			(layers "*.Cu" "*.Mask")
			(clearance 0.381)
			(thermal_gap 0.381)
		)
		(pad "" np_thru_hole circle
			(at 2.8829 1.27 270)
			(size 1.0414 1.0414)
			(drill 1.0414)
			(layers "*.Cu" "*.Mask")
			(clearance 0.381)
			(thermal_gap 0.381)
		)
		(pad "1" smd rect
			(at -0.8255 -0.249936 270)
			(size 0.3048 0.508)
			(layers "B.Cu" "B.Mask" "B.Paste")
			(net "DELTA_L_85_10INCH_IN5_DN")
		)
		(pad "2" smd rect
			(at -0.8255 0.249936 270)
			(size 0.3048 0.508)
			(layers "B.Cu" "B.Mask" "B.Paste")
			(net "DELTA_L_85_10INCH_IN5_DP")
		)
		(pad "3" smd circle
			(at 0 0 180)
			(size 0 0)
			(layers "B.Cu" "B.Mask" "B.Paste")
			(net "DELTA_L_GND_1")
		)
		(zone
			(layers "F.Cu" "B.Cu" "In1.Cu" "In2.Cu" "In3.Cu" "In4.Cu" "In5.Cu" "In6.Cu"
				"In7.Cu" "In8.Cu" "In9.Cu" "In10.Cu" "In11.Cu" "In12.Cu" "In13.Cu" "In14.Cu"
				"In15.Cu" "In16.Cu"
			)
			(hatch none 0.5)
			(connect_pads
				(clearance 0)
			)
			(min_thickness 0.25)
			(keepout
				(tracks not_allowed)
				(vias allowed)
				(pads allowed)
				(copperpour not_allowed)
				(footprints allowed)
			)
			(placement
				(enabled no)
				(sheetname "")
			)
			(fill
				(thermal_gap 0.5)
				(thermal_bridge_width 0.5)
				(island_removal_mode 0)
			)
			(polygon
				(pts
					(arc
						(start 326.700388 6.733794)
						(mid 324.846188 6.733794)
						(end 326.700388 6.733794)
					)
				)
			)
		)
		(zone
			(layers "F.Cu" "B.Cu" "In1.Cu" "In2.Cu" "In3.Cu" "In4.Cu" "In5.Cu" "In6.Cu"
				"In7.Cu" "In8.Cu" "In9.Cu" "In10.Cu" "In11.Cu" "In12.Cu" "In13.Cu" "In14.Cu"
				"In15.Cu" "In16.Cu"
			)
			(hatch none 0.5)
			(connect_pads
				(clearance 0)
			)
			(min_thickness 0.25)
			(keepout
				(tracks not_allowed)
				(vias allowed)
				(pads allowed)
				(copperpour not_allowed)
				(footprints allowed)
			)
			(placement
				(enabled no)
				(sheetname "")
			)
			(fill
				(thermal_gap 0.5)
				(thermal_bridge_width 0.5)
				(island_removal_mode 0)
			)
			(polygon
				(pts
					(arc
						(start 326.700388 9.273794)
						(mid 324.846188 9.273794)
						(end 326.700388 9.273794)
					)
				)
			)
		)
		(zone
			(layers "F.Cu" "B.Cu" "In1.Cu" "In2.Cu" "In3.Cu" "In4.Cu" "In5.Cu" "In6.Cu"
				"In7.Cu" "In8.Cu" "In9.Cu" "In10.Cu" "In11.Cu" "In12.Cu" "In13.Cu" "In14.Cu"
				"In15.Cu" "In16.Cu"
			)
			(hatch none 0.5)
			(connect_pads
				(clearance 0)
			)
			(min_thickness 0.25)
			(keepout
				(tracks not_allowed)
				(vias allowed)
				(pads allowed)
				(copperpour not_allowed)
				(footprints allowed)
			)
			(placement
				(enabled no)
				(sheetname "")
			)
			(fill
				(thermal_gap 0.5)
				(thermal_bridge_width 0.5)
				(island_removal_mode 0)
			)
			(polygon
				(pts
					(arc
						(start 333.050388 6.733794)
						(mid 331.196188 6.733794)
						(end 333.050388 6.733794)
					)
				)
			)
		)
		(zone
			(layers "F.Cu" "B.Cu" "In1.Cu" "In2.Cu" "In3.Cu" "In4.Cu" "In5.Cu" "In6.Cu"
				"In7.Cu" "In8.Cu" "In9.Cu" "In10.Cu" "In11.Cu" "In12.Cu" "In13.Cu" "In14.Cu"
				"In15.Cu" "In16.Cu"
			)
			(hatch none 0.5)
			(connect_pads
				(clearance 0)
			)
			(min_thickness 0.25)
			(keepout
				(tracks not_allowed)
				(vias allowed)
				(pads allowed)
				(copperpour not_allowed)
				(footprints allowed)
			)
			(placement
				(enabled no)
				(sheetname "")
			)
			(fill
				(thermal_gap 0.5)
				(thermal_bridge_width 0.5)
				(island_removal_mode 0)
			)
			(polygon
				(pts
					(arc
						(start 333.050388 9.273794)
						(mid 331.196188 9.273794)
						(end 333.050388 9.273794)
					)
				)
			)
		)
		(zone
			(layer "B.Cu")
			(hatch none 0.5)
			(connect_pads
				(clearance 0)
			)
			(min_thickness 0.25)
			(keepout
				(tracks not_allowed)
				(vias allowed)
				(pads allowed)
				(copperpour not_allowed)
				(footprints allowed)
			)
			(placement
				(enabled no)
				(sheetname "")
			)
			(fill
				(thermal_gap 0.5)
				(thermal_bridge_width 0.5)
				(island_removal_mode 0)
			)
			(polygon
				(pts
					(xy 328.122788 7.455154) (xy 328.122788 7.550658) (xy 328.719688 7.550658) (xy 328.719688 7.957058)
					(xy 328.122788 7.957058) (xy 328.122788 8.05053) (xy 328.719688 8.05053) (xy 328.719688 8.45693)
					(xy 328.122788 8.45693) (xy 328.122788 8.552434) (xy 328.821288 8.552434) (xy 328.821288 7.455154)
				)
			)
		)
	)
	(footprint ""
		(layer "B.Cu")
		(at 416.996626 -181.854602 180)
		(property "Reference" "PR102"
			(at 0 0 0)
			(layer "B.SilkS")
			(hide yes)
			(effects
				(font
					(size 1.27 1.27)
				)
				(justify mirror)
			)
		)
		(property "Value" ""
			(at 0 0 0)
			(layer "B.Fab")
			(effects
				(font
					(size 1.27 1.27)
				)
				(justify mirror)
			)
		)
		(duplicate_pad_numbers_are_jumpers no)
		(fp_line
			(start 0.7874 0.4064)
			(end 0.7874 -0.4064)
			(stroke
				(width 0.1524)
				(type default)
			)
			(layer "B.SilkS")
		)
		(fp_line
			(start 0.7874 -0.4064)
			(end -0.7874 -0.4064)
			(stroke
				(width 0.1524)
				(type default)
			)
			(layer "B.SilkS")
		)
		(fp_line
			(start -0.7874 0.4064)
			(end 0.7874 0.4064)
			(stroke
				(width 0.1524)
				(type default)
			)
			(layer "B.SilkS")
		)
		(fp_line
			(start -0.7874 -0.4064)
			(end -0.7874 0.4064)
			(stroke
				(width 0.1524)
				(type default)
			)
			(layer "B.SilkS")
		)
		(fp_line
			(start 0.67945 0.3048)
			(end 0.67945 -0.305054)
			(stroke
				(width 0.1)
				(type default)
			)
			(layer "B.Fab")
		)
		(fp_line
			(start 0.67945 -0.305054)
			(end 0.12065 -0.305054)
			(stroke
				(width 0.1)
				(type default)
			)
			(layer "B.Fab")
		)
		(fp_line
			(start 0.12065 0.3048)
			(end 0.67945 0.3048)
			(stroke
				(width 0.1)
				(type default)
			)
			(layer "B.Fab")
		)
		(fp_line
			(start 0.12065 0.2794)
			(end 0.12065 0.3048)
			(stroke
				(width 0.1)
				(type default)
			)
			(layer "B.Fab")
		)
		(fp_line
			(start 0.12065 -0.2794)
			(end -0.12065 -0.2794)
			(stroke
				(width 0.1)
				(type default)
			)
			(layer "B.Fab")
		)
		(fp_line
			(start 0.12065 -0.305054)
			(end 0.12065 -0.2794)
			(stroke
				(width 0.1)
				(type default)
			)
			(layer "B.Fab")
		)
		(fp_line
			(start -0.120396 0.3048)
			(end -0.120396 0.2794)
			(stroke
				(width 0.1)
				(type default)
			)
			(layer "B.Fab")
		)
		(fp_line
			(start -0.120396 0.2794)
			(end 0.12065 0.2794)
			(stroke
				(width 0.1)
				(type default)
			)
			(layer "B.Fab")
		)
		(fp_line
			(start -0.12065 -0.2794)
			(end -0.12065 -0.3048)
			(stroke
				(width 0.1)
				(type default)
			)
			(layer "B.Fab")
		)
		(fp_line
			(start -0.12065 -0.3048)
			(end -0.67945 -0.3048)
			(stroke
				(width 0.1)
				(type default)
			)
			(layer "B.Fab")
		)
		(fp_line
			(start -0.67945 0.3048)
			(end -0.120396 0.3048)
			(stroke
				(width 0.1)
				(type default)
			)
			(layer "B.Fab")
		)
		(fp_line
			(start -0.67945 -0.3048)
			(end -0.67945 0.3048)
			(stroke
				(width 0.1)
				(type default)
			)
			(layer "B.Fab")
		)
		(pad "1" smd circle
			(at 0.40005 0)
			(size 0 0)
			(layers "B.Cu" "B.Mask" "B.Paste")
			(net "PVCCFA_EHV_CPU0_PVCC")
		)
		(pad "2" smd circle
			(at -0.40005 0)
			(size 0 0)
			(layers "B.Cu" "B.Mask" "B.Paste")
			(net "PVCCINFAON_CPU0_VDD2")
		)
	)
	(footprint ""
		(layer "B.Cu")
		(at 243.001038 -102.528624 180)
		(property "Reference" "R1526"
			(at 0 0 0)
			(layer "B.SilkS")
			(hide yes)
			(effects
				(font
					(size 1.27 1.27)
				)
				(justify mirror)
			)
		)
		(property "Value" ""
			(at 0 0 0)
			(layer "B.Fab")
			(effects
				(font
					(size 1.27 1.27)
				)
				(justify mirror)
			)
		)
		(duplicate_pad_numbers_are_jumpers no)
		(fp_line
			(start 0.7874 0.4064)
			(end 0.7874 -0.4064)
			(stroke
				(width 0.1524)
				(type default)
			)
			(layer "B.SilkS")
		)
		(fp_line
			(start 0.7874 -0.4064)
			(end -0.7874 -0.4064)
			(stroke
				(width 0.1524)
				(type default)
			)
			(layer "B.SilkS")
		)
		(fp_line
			(start -0.7874 0.4064)
			(end 0.7874 0.4064)
			(stroke
				(width 0.1524)
				(type default)
			)
			(layer "B.SilkS")
		)
		(fp_line
			(start -0.7874 -0.4064)
			(end -0.7874 0.4064)
			(stroke
				(width 0.1524)
				(type default)
			)
			(layer "B.SilkS")
		)
		(fp_line
			(start 0.67945 0.3048)
			(end 0.67945 -0.305054)
			(stroke
				(width 0.1)
				(type default)
			)
			(layer "B.Fab")
		)
		(fp_line
			(start 0.67945 -0.305054)
			(end 0.12065 -0.305054)
			(stroke
				(width 0.1)
				(type default)
			)
			(layer "B.Fab")
		)
		(fp_line
			(start 0.12065 0.3048)
			(end 0.67945 0.3048)
			(stroke
				(width 0.1)
				(type default)
			)
			(layer "B.Fab")
		)
		(fp_line
			(start 0.12065 0.2794)
			(end 0.12065 0.3048)
			(stroke
				(width 0.1)
				(type default)
			)
			(layer "B.Fab")
		)
		(fp_line
			(start 0.12065 -0.2794)
			(end -0.12065 -0.2794)
			(stroke
				(width 0.1)
				(type default)
			)
			(layer "B.Fab")
		)
		(fp_line
			(start 0.12065 -0.305054)
			(end 0.12065 -0.2794)
			(stroke
				(width 0.1)
				(type default)
			)
			(layer "B.Fab")
		)
		(fp_line
			(start -0.120396 0.3048)
			(end -0.120396 0.2794)
			(stroke
				(width 0.1)
				(type default)
			)
			(layer "B.Fab")
		)
		(fp_line
			(start -0.120396 0.2794)
			(end 0.12065 0.2794)
			(stroke
				(width 0.1)
				(type default)
			)
			(layer "B.Fab")
		)
		(fp_line
			(start -0.12065 -0.2794)
			(end -0.12065 -0.3048)
			(stroke
				(width 0.1)
				(type default)
			)
			(layer "B.Fab")
		)
		(fp_line
			(start -0.12065 -0.3048)
			(end -0.67945 -0.3048)
			(stroke
				(width 0.1)
				(type default)
			)
			(layer "B.Fab")
		)
		(fp_line
			(start -0.67945 0.3048)
			(end -0.120396 0.3048)
			(stroke
				(width 0.1)
				(type default)
			)
			(layer "B.Fab")
		)
		(fp_line
			(start -0.67945 -0.3048)
			(end -0.67945 0.3048)
			(stroke
				(width 0.1)
				(type default)
			)
			(layer "B.Fab")
		)
		(pad "1" smd circle
			(at 0.40005 0)
			(size 0 0)
			(layers "B.Cu" "B.Mask" "B.Paste")
			(net "SMB_HOST_3V3AUX_SDA_R")
		)
		(pad "2" smd circle
			(at -0.40005 0)
			(size 0 0)
			(layers "B.Cu" "B.Mask" "B.Paste")
			(net "SMB_HOST_CLK_3V3AUX_SDA")
		)
	)
	(footprint ""
		(layer "B.Cu")
		(at 370.734082 -337.546442 -90)
		(property "Reference" "PC282_P0_4"
			(at 0 0 90)
			(layer "B.SilkS")
			(hide yes)
			(effects
				(font
					(size 1.27 1.27)
				)
				(justify mirror)
			)
		)
		(property "Value" ""
			(at 0 0 90)
			(layer "B.Fab")
			(effects
				(font
					(size 1.27 1.27)
				)
				(justify mirror)
			)
		)
		(duplicate_pad_numbers_are_jumpers no)
		(fp_line
			(start -1.524 0.762)
			(end 1.524 0.762)
			(stroke
				(width 0.1524)
				(type default)
			)
			(layer "B.SilkS")
		)
		(fp_line
			(start 1.524 0.762)
			(end 1.524 -0.762)
			(stroke
				(width 0.1524)
				(type default)
			)
			(layer "B.SilkS")
		)
		(fp_line
			(start -1.524 -0.762)
			(end -1.524 0.762)
			(stroke
				(width 0.1524)
				(type default)
			)
			(layer "B.SilkS")
		)
		(fp_line
			(start 1.524 -0.762)
			(end -1.524 -0.762)
			(stroke
				(width 0.1524)
				(type default)
			)
			(layer "B.SilkS")
		)
		(fp_line
			(start -1.1049 0.724916)
			(end -1.1049 -0.724916)
			(stroke
				(width 0.1)
				(type default)
			)
			(layer "B.Fab")
		)
		(fp_line
			(start 1.1049 0.724916)
			(end -1.1049 0.724916)
			(stroke
				(width 0.1)
				(type default)
			)
			(layer "B.Fab")
		)
		(fp_line
			(start -1.1049 -0.724916)
			(end 1.1049 -0.724916)
			(stroke
				(width 0.1)
				(type default)
			)
			(layer "B.Fab")
		)
		(fp_line
			(start 1.1049 -0.724916)
			(end 1.1049 0.724916)
			(stroke
				(width 0.1)
				(type default)
			)
			(layer "B.Fab")
		)
		(pad "1" smd rect
			(at 0.889 0 270)
			(size 1.016 1.27)
			(layers "B.Cu" "B.Mask" "B.Paste")
			(net "SW_P12V_PVCCIN_CPU0_FLT")
		)
		(pad "2" smd rect
			(at -0.889 0 270)
			(size 1.016 1.27)
			(layers "B.Cu" "B.Mask" "B.Paste")
			(net "GND")
		)
	)
)
